(kicad_pcb
	(version 20260206)
	(generator "pcbnew")
	(generator_version "10.0")
	(general
		(thickness 1.6)
		(legacy_teardrops no)
	)
	(paper "A4")
	(title_block
		(title "01162023_DA0F0TEBIF0_F0T_Expander_BD_F_brd_V02_OCP.brd")
		(comment 1 "Grand Teton / footprints 6949-6954 of 9728")
	)
	(layers
		(0 "F.Cu" signal "TOP")
		(4 "In1.Cu" signal "GND")
		(6 "In2.Cu" signal "VCC")
		(8 "In3.Cu" signal "VCC1")
		(10 "In4.Cu" signal "GND1")
		(12 "In5.Cu" signal "IN1")
		(14 "In6.Cu" signal "GND2")
		(16 "In7.Cu" signal "IN2")
		(18 "In8.Cu" signal "GND3")
		(20 "In9.Cu" signal "IN3")
		(22 "In10.Cu" signal "GND4")
		(24 "In11.Cu" signal "IN4")
		(26 "In12.Cu" signal "GND5")
		(28 "In13.Cu" signal "IN5")
		(30 "In14.Cu" signal "GND6")
		(32 "In15.Cu" signal "IN6")
		(34 "In16.Cu" signal "GND7")
		(2 "B.Cu" signal "BOTTOM")
		(9 "F.Adhes" user "F.Adhesive")
		(11 "B.Adhes" user "B.Adhesive")
		(13 "F.Paste" user "Package Geometry/Pastemask Top")
		(15 "B.Paste" user "Package Geometry/Pastemask Bottom")
		(5 "F.SilkS" user "Ref Des/Silkscreen Top")
		(7 "B.SilkS" user "Ref Des/Silkscreen Bottom")
		(1 "F.Mask" user "Board Geometry/Soldermask Top")
		(3 "B.Mask" user "Board Geometry/Soldermask Bottom")
		(17 "Dwgs.User" user "User.Drawings")
		(19 "Cmts.User" user "User.Comments")
		(21 "Eco1.User" user "User.Eco1")
		(23 "Eco2.User" user "User.Eco2")
		(25 "Edge.Cuts" user "Board Geometry/Outline")
		(27 "Margin" user)
		(31 "F.CrtYd" user "Package Geometry/Place Bound Top")
		(29 "B.CrtYd" user "Package Geometry/Place Bound Bottom")
		(35 "F.Fab" user "Ref Des/Assembly Top")
		(33 "B.Fab" user "Ref Des/Assembly Bottom")
	)
	(footprint ""
		(layer "F.Cu")
		(at 2.099056 -40.01262 -90)
		(property "Reference" "PC668"
			(at 0 0 270)
			(layer "F.SilkS")
			(hide yes)
			(effects
				(font
					(size 1.27 1.27)
				)
			)
		)
		(property "Value" ""
			(at 0 0 270)
			(layer "F.Fab")
			(effects
				(font
					(size 1.27 1.27)
				)
			)
		)
		(duplicate_pad_numbers_are_jumpers no)
		(fp_line
			(start -0.7874 0.4064)
			(end -0.7874 -0.4064)
			(stroke
				(width 0.1524)
				(type default)
			)
			(layer "F.SilkS")
		)
		(fp_line
			(start 0.7874 0.4064)
			(end -0.7874 0.4064)
			(stroke
				(width 0.1524)
				(type default)
			)
			(layer "F.SilkS")
		)
		(fp_line
			(start -0.7874 -0.4064)
			(end 0.7874 -0.4064)
			(stroke
				(width 0.1524)
				(type default)
			)
			(layer "F.SilkS")
		)
		(fp_line
			(start 0.7874 -0.4064)
			(end 0.7874 0.4064)
			(stroke
				(width 0.1524)
				(type default)
			)
			(layer "F.SilkS")
		)
		(fp_line
			(start -0.67945 0.3048)
			(end -0.67945 -0.305054)
			(stroke
				(width 0.1)
				(type default)
			)
			(layer "F.Fab")
		)
		(fp_line
			(start -0.12065 0.3048)
			(end -0.67945 0.3048)
			(stroke
				(width 0.1)
				(type default)
			)
			(layer "F.Fab")
		)
		(fp_line
			(start 0.120396 0.3048)
			(end 0.120396 0.2794)
			(stroke
				(width 0.1)
				(type default)
			)
			(layer "F.Fab")
		)
		(fp_line
			(start 0.67945 0.3048)
			(end 0.120396 0.3048)
			(stroke
				(width 0.1)
				(type default)
			)
			(layer "F.Fab")
		)
		(fp_line
			(start -0.12065 0.2794)
			(end -0.12065 0.3048)
			(stroke
				(width 0.1)
				(type default)
			)
			(layer "F.Fab")
		)
		(fp_line
			(start 0.120396 0.2794)
			(end -0.12065 0.2794)
			(stroke
				(width 0.1)
				(type default)
			)
			(layer "F.Fab")
		)
		(fp_line
			(start -0.12065 -0.2794)
			(end 0.12065 -0.2794)
			(stroke
				(width 0.1)
				(type default)
			)
			(layer "F.Fab")
		)
		(fp_line
			(start 0.12065 -0.2794)
			(end 0.12065 -0.3048)
			(stroke
				(width 0.1)
				(type default)
			)
			(layer "F.Fab")
		)
		(fp_line
			(start 0.12065 -0.3048)
			(end 0.67945 -0.3048)
			(stroke
				(width 0.1)
				(type default)
			)
			(layer "F.Fab")
		)
		(fp_line
			(start 0.67945 -0.3048)
			(end 0.67945 0.3048)
			(stroke
				(width 0.1)
				(type default)
			)
			(layer "F.Fab")
		)
		(fp_line
			(start -0.67945 -0.305054)
			(end -0.12065 -0.305054)
			(stroke
				(width 0.1)
				(type default)
			)
			(layer "F.Fab")
		)
		(fp_line
			(start -0.12065 -0.305054)
			(end -0.12065 -0.2794)
			(stroke
				(width 0.1)
				(type default)
			)
			(layer "F.Fab")
		)
		(pad "1" smd circle
			(at -0.40005 0 270)
			(size 0 0)
			(layers "F.Cu" "F.Mask" "F.Paste")
			(net "P3V3_AUX")
		)
		(pad "2" smd circle
			(at 0.40005 0 270)
			(size 0 0)
			(layers "F.Cu" "F.Mask" "F.Paste")
			(net "GND")
		)
	)
	(footprint ""
		(layer "F.Cu")
		(at 2.232152 -251.312426 -90)
		(property "Reference" "C4240"
			(at 0 0 270)
			(layer "F.SilkS")
			(hide yes)
			(effects
				(font
					(size 1.27 1.27)
				)
			)
		)
		(property "Value" ""
			(at 0 0 270)
			(layer "F.Fab")
			(effects
				(font
					(size 1.27 1.27)
				)
			)
		)
		(duplicate_pad_numbers_are_jumpers no)
		(fp_line
			(start -1.2954 0.5842)
			(end -1.2954 -0.5842)
			(stroke
				(width 0.1524)
				(type default)
			)
			(layer "F.SilkS")
		)
		(fp_line
			(start 1.2954 0.5842)
			(end -1.2954 0.5842)
			(stroke
				(width 0.1524)
				(type default)
			)
			(layer "F.SilkS")
		)
		(fp_line
			(start -1.2954 -0.5842)
			(end 1.2954 -0.5842)
			(stroke
				(width 0.1524)
				(type default)
			)
			(layer "F.SilkS")
		)
		(fp_line
			(start 1.2954 -0.5842)
			(end 1.2954 0.5842)
			(stroke
				(width 0.1524)
				(type default)
			)
			(layer "F.SilkS")
		)
		(fp_line
			(start -0.8636 0.4572)
			(end -0.8636 0.4064)
			(stroke
				(width 0.1)
				(type default)
			)
			(layer "F.Fab")
		)
		(fp_line
			(start 0.8636 0.4572)
			(end -0.8636 0.4572)
			(stroke
				(width 0.1)
				(type default)
			)
			(layer "F.Fab")
		)
		(fp_line
			(start -1.1938 0.4064)
			(end -1.1938 -0.4064)
			(stroke
				(width 0.1)
				(type default)
			)
			(layer "F.Fab")
		)
		(fp_line
			(start -0.8636 0.4064)
			(end -1.1938 0.4064)
			(stroke
				(width 0.1)
				(type default)
			)
			(layer "F.Fab")
		)
		(fp_line
			(start 0.8636 0.4064)
			(end 0.8636 0.4572)
			(stroke
				(width 0.1)
				(type default)
			)
			(layer "F.Fab")
		)
		(fp_line
			(start 1.1938 0.4064)
			(end 0.8636 0.4064)
			(stroke
				(width 0.1)
				(type default)
			)
			(layer "F.Fab")
		)
		(fp_line
			(start -1.1938 -0.4064)
			(end -0.8636 -0.4064)
			(stroke
				(width 0.1)
				(type default)
			)
			(layer "F.Fab")
		)
		(fp_line
			(start -0.8636 -0.4064)
			(end -0.8636 -0.4572)
			(stroke
				(width 0.1)
				(type default)
			)
			(layer "F.Fab")
		)
		(fp_line
			(start 0.8636 -0.4064)
			(end 1.1938 -0.4064)
			(stroke
				(width 0.1)
				(type default)
			)
			(layer "F.Fab")
		)
		(fp_line
			(start 1.1938 -0.4064)
			(end 1.1938 0.4064)
			(stroke
				(width 0.1)
				(type default)
			)
			(layer "F.Fab")
		)
		(fp_line
			(start -0.8636 -0.4572)
			(end 0.8636 -0.4572)
			(stroke
				(width 0.1)
				(type default)
			)
			(layer "F.Fab")
		)
		(fp_line
			(start 0.8636 -0.4572)
			(end 0.8636 -0.4064)
			(stroke
				(width 0.1)
				(type default)
			)
			(layer "F.Fab")
		)
		(pad "1" smd rect
			(at -0.7366 0 180)
			(size 0.7112 0.8128)
			(layers "F.Cu" "F.Mask" "F.Paste")
			(net "P1V25_SERDES_VDDPLL_PEX0_C6")
		)
		(pad "2" smd rect
			(at 0.7366 0 180)
			(size 0.7112 0.8128)
			(layers "F.Cu" "F.Mask" "F.Paste")
			(net "GND")
		)
	)
	(footprint ""
		(layer "F.Cu")
		(at 444.908432 -224.700846)
		(property "Reference" "R6606"
			(at 0 0 0)
			(layer "F.SilkS")
			(hide yes)
			(effects
				(font
					(size 1.27 1.27)
				)
			)
		)
		(property "Value" ""
			(at 0 0 0)
			(layer "F.Fab")
			(effects
				(font
					(size 1.27 1.27)
				)
			)
		)
		(duplicate_pad_numbers_are_jumpers no)
		(fp_line
			(start -0.7874 -0.4064)
			(end 0.7874 -0.4064)
			(stroke
				(width 0.1524)
				(type default)
			)
			(layer "F.SilkS")
		)
		(fp_line
			(start -0.7874 0.4064)
			(end -0.7874 -0.4064)
			(stroke
				(width 0.1524)
				(type default)
			)
			(layer "F.SilkS")
		)
		(fp_line
			(start 0.7874 -0.4064)
			(end 0.7874 0.4064)
			(stroke
				(width 0.1524)
				(type default)
			)
			(layer "F.SilkS")
		)
		(fp_line
			(start 0.7874 0.4064)
			(end -0.7874 0.4064)
			(stroke
				(width 0.1524)
				(type default)
			)
			(layer "F.SilkS")
		)
		(fp_line
			(start -0.67945 -0.305054)
			(end -0.12065 -0.305054)
			(stroke
				(width 0.1)
				(type default)
			)
			(layer "F.Fab")
		)
		(fp_line
			(start -0.67945 0.3048)
			(end -0.67945 -0.305054)
			(stroke
				(width 0.1)
				(type default)
			)
			(layer "F.Fab")
		)
		(fp_line
			(start -0.12065 -0.305054)
			(end -0.12065 -0.2794)
			(stroke
				(width 0.1)
				(type default)
			)
			(layer "F.Fab")
		)
		(fp_line
			(start -0.12065 -0.2794)
			(end 0.12065 -0.2794)
			(stroke
				(width 0.1)
				(type default)
			)
			(layer "F.Fab")
		)
		(fp_line
			(start -0.12065 0.2794)
			(end -0.12065 0.3048)
			(stroke
				(width 0.1)
				(type default)
			)
			(layer "F.Fab")
		)
		(fp_line
			(start -0.12065 0.3048)
			(end -0.67945 0.3048)
			(stroke
				(width 0.1)
				(type default)
			)
			(layer "F.Fab")
		)
		(fp_line
			(start 0.120396 0.2794)
			(end -0.12065 0.2794)
			(stroke
				(width 0.1)
				(type default)
			)
			(layer "F.Fab")
		)
		(fp_line
			(start 0.120396 0.3048)
			(end 0.120396 0.2794)
			(stroke
				(width 0.1)
				(type default)
			)
			(layer "F.Fab")
		)
		(fp_line
			(start 0.12065 -0.3048)
			(end 0.67945 -0.3048)
			(stroke
				(width 0.1)
				(type default)
			)
			(layer "F.Fab")
		)
		(fp_line
			(start 0.12065 -0.2794)
			(end 0.12065 -0.3048)
			(stroke
				(width 0.1)
				(type default)
			)
			(layer "F.Fab")
		)
		(fp_line
			(start 0.67945 -0.3048)
			(end 0.67945 0.3048)
			(stroke
				(width 0.1)
				(type default)
			)
			(layer "F.Fab")
		)
		(fp_line
			(start 0.67945 0.3048)
			(end 0.120396 0.3048)
			(stroke
				(width 0.1)
				(type default)
			)
			(layer "F.Fab")
		)
		(pad "1" smd circle
			(at -0.40005 0)
			(size 0 0)
			(layers "F.Cu" "F.Mask" "F.Paste")
			(net "UART_PEX2_SDB_BUF_R_TX")
		)
		(pad "2" smd circle
			(at 0.40005 0)
			(size 0 0)
			(layers "F.Cu" "F.Mask" "F.Paste")
			(net "UART_PEX2_SDB_CP2108_TX")
		)
	)
	(footprint ""
		(layer "F.Cu")
		(at 104.267762 -52.035456 180)
		(property "Reference" "R867"
			(at 0 0 180)
			(layer "F.SilkS")
			(hide yes)
			(effects
				(font
					(size 1.27 1.27)
				)
			)
		)
		(property "Value" ""
			(at 0 0 180)
			(layer "F.Fab")
			(effects
				(font
					(size 1.27 1.27)
				)
			)
		)
		(duplicate_pad_numbers_are_jumpers no)
		(fp_line
			(start 0.7874 0.4064)
			(end -0.7874 0.4064)
			(stroke
				(width 0.1524)
				(type default)
			)
			(layer "F.SilkS")
		)
		(fp_line
			(start 0.7874 -0.4064)
			(end 0.7874 0.4064)
			(stroke
				(width 0.1524)
				(type default)
			)
			(layer "F.SilkS")
		)
		(fp_line
			(start -0.7874 0.4064)
			(end -0.7874 -0.4064)
			(stroke
				(width 0.1524)
				(type default)
			)
			(layer "F.SilkS")
		)
		(fp_line
			(start -0.7874 -0.4064)
			(end 0.7874 -0.4064)
			(stroke
				(width 0.1524)
				(type default)
			)
			(layer "F.SilkS")
		)
		(fp_line
			(start 0.67945 0.3048)
			(end 0.120396 0.3048)
			(stroke
				(width 0.1)
				(type default)
			)
			(layer "F.Fab")
		)
		(fp_line
			(start 0.67945 -0.3048)
			(end 0.67945 0.3048)
			(stroke
				(width 0.1)
				(type default)
			)
			(layer "F.Fab")
		)
		(fp_line
			(start 0.12065 -0.2794)
			(end 0.12065 -0.3048)
			(stroke
				(width 0.1)
				(type default)
			)
			(layer "F.Fab")
		)
		(fp_line
			(start 0.12065 -0.3048)
			(end 0.67945 -0.3048)
			(stroke
				(width 0.1)
				(type default)
			)
			(layer "F.Fab")
		)
		(fp_line
			(start 0.120396 0.3048)
			(end 0.120396 0.2794)
			(stroke
				(width 0.1)
				(type default)
			)
			(layer "F.Fab")
		)
		(fp_line
			(start 0.120396 0.2794)
			(end -0.12065 0.2794)
			(stroke
				(width 0.1)
				(type default)
			)
			(layer "F.Fab")
		)
		(fp_line
			(start -0.12065 0.3048)
			(end -0.67945 0.3048)
			(stroke
				(width 0.1)
				(type default)
			)
			(layer "F.Fab")
		)
		(fp_line
			(start -0.12065 0.2794)
			(end -0.12065 0.3048)
			(stroke
				(width 0.1)
				(type default)
			)
			(layer "F.Fab")
		)
		(fp_line
			(start -0.12065 -0.2794)
			(end 0.12065 -0.2794)
			(stroke
				(width 0.1)
				(type default)
			)
			(layer "F.Fab")
		)
		(fp_line
			(start -0.12065 -0.305054)
			(end -0.12065 -0.2794)
			(stroke
				(width 0.1)
				(type default)
			)
			(layer "F.Fab")
		)
		(fp_line
			(start -0.67945 0.3048)
			(end -0.67945 -0.305054)
			(stroke
				(width 0.1)
				(type default)
			)
			(layer "F.Fab")
		)
		(fp_line
			(start -0.67945 -0.305054)
			(end -0.12065 -0.305054)
			(stroke
				(width 0.1)
				(type default)
			)
			(layer "F.Fab")
		)
		(pad "1" smd circle
			(at -0.40005 0 180)
			(size 0 0)
			(layers "F.Cu" "F.Mask" "F.Paste")
			(net "P3V3_AUX")
		)
		(pad "2" smd circle
			(at 0.40005 0 180)
			(size 0 0)
			(layers "F.Cu" "F.Mask" "F.Paste")
			(net "PWRGD_P12V_SSD3")
		)
	)
	(footprint ""
		(layer "F.Cu")
		(at 72.947276 -21.37156)
		(property "Reference" "C3889"
			(at 0 0 0)
			(layer "F.SilkS")
			(hide yes)
			(effects
				(font
					(size 1.27 1.27)
				)
			)
		)
		(property "Value" ""
			(at 0 0 0)
			(layer "F.Fab")
			(effects
				(font
					(size 1.27 1.27)
				)
			)
		)
		(duplicate_pad_numbers_are_jumpers no)
		(fp_line
			(start -0.7874 -0.4064)
			(end 0.7874 -0.4064)
			(stroke
				(width 0.1524)
				(type default)
			)
			(layer "F.SilkS")
		)
		(fp_line
			(start -0.7874 0.4064)
			(end -0.7874 -0.4064)
			(stroke
				(width 0.1524)
				(type default)
			)
			(layer "F.SilkS")
		)
		(fp_line
			(start 0.7874 -0.4064)
			(end 0.7874 0.4064)
			(stroke
				(width 0.1524)
				(type default)
			)
			(layer "F.SilkS")
		)
		(fp_line
			(start 0.7874 0.4064)
			(end -0.7874 0.4064)
			(stroke
				(width 0.1524)
				(type default)
			)
			(layer "F.SilkS")
		)
		(fp_line
			(start -0.67945 -0.305054)
			(end -0.12065 -0.305054)
			(stroke
				(width 0.1)
				(type default)
			)
			(layer "F.Fab")
		)
		(fp_line
			(start -0.67945 0.3048)
			(end -0.67945 -0.305054)
			(stroke
				(width 0.1)
				(type default)
			)
			(layer "F.Fab")
		)
		(fp_line
			(start -0.12065 -0.305054)
			(end -0.12065 -0.2794)
			(stroke
				(width 0.1)
				(type default)
			)
			(layer "F.Fab")
		)
		(fp_line
			(start -0.12065 -0.2794)
			(end 0.12065 -0.2794)
			(stroke
				(width 0.1)
				(type default)
			)
			(layer "F.Fab")
		)
		(fp_line
			(start -0.12065 0.2794)
			(end -0.12065 0.3048)
			(stroke
				(width 0.1)
				(type default)
			)
			(layer "F.Fab")
		)
		(fp_line
			(start -0.12065 0.3048)
			(end -0.67945 0.3048)
			(stroke
				(width 0.1)
				(type default)
			)
			(layer "F.Fab")
		)
		(fp_line
			(start 0.120396 0.2794)
			(end -0.12065 0.2794)
			(stroke
				(width 0.1)
				(type default)
			)
			(layer "F.Fab")
		)
		(fp_line
			(start 0.120396 0.3048)
			(end 0.120396 0.2794)
			(stroke
				(width 0.1)
				(type default)
			)
			(layer "F.Fab")
		)
		(fp_line
			(start 0.12065 -0.3048)
			(end 0.67945 -0.3048)
			(stroke
				(width 0.1)
				(type default)
			)
			(layer "F.Fab")
		)
		(fp_line
			(start 0.12065 -0.2794)
			(end 0.12065 -0.3048)
			(stroke
				(width 0.1)
				(type default)
			)
			(layer "F.Fab")
		)
		(fp_line
			(start 0.67945 -0.3048)
			(end 0.67945 0.3048)
			(stroke
				(width 0.1)
				(type default)
			)
			(layer "F.Fab")
		)
		(fp_line
			(start 0.67945 0.3048)
			(end 0.120396 0.3048)
			(stroke
				(width 0.1)
				(type default)
			)
			(layer "F.Fab")
		)
		(pad "1" smd circle
			(at -0.40005 0)
			(size 0 0)
			(layers "F.Cu" "F.Mask" "F.Paste")
			(net "P12V_SSD2")
		)
		(pad "2" smd circle
			(at 0.40005 0)
			(size 0 0)
			(layers "F.Cu" "F.Mask" "F.Paste")
			(net "GND")
		)
	)
	(footprint ""
		(layer "F.Cu")
		(at 366.211866 -146.263614 180)
		(property "Reference" "C620"
			(at 0 0 180)
			(layer "F.SilkS")
			(hide yes)
			(effects
				(font
					(size 1.27 1.27)
				)
			)
		)
		(property "Value" ""
			(at 0 0 180)
			(layer "F.Fab")
			(effects
				(font
					(size 1.27 1.27)
				)
			)
		)
		(duplicate_pad_numbers_are_jumpers no)
		(fp_line
			(start 0.7874 0.4064)
			(end -0.7874 0.4064)
			(stroke
				(width 0.1524)
				(type default)
			)
			(layer "F.SilkS")
		)
		(fp_line
			(start 0.7874 -0.4064)
			(end 0.7874 0.4064)
			(stroke
				(width 0.1524)
				(type default)
			)
			(layer "F.SilkS")
		)
		(fp_line
			(start -0.7874 0.4064)
			(end -0.7874 -0.4064)
			(stroke
				(width 0.1524)
				(type default)
			)
			(layer "F.SilkS")
		)
		(fp_line
			(start -0.7874 -0.4064)
			(end 0.7874 -0.4064)
			(stroke
				(width 0.1524)
				(type default)
			)
			(layer "F.SilkS")
		)
		(fp_line
			(start 0.67945 0.3048)
			(end 0.120396 0.3048)
			(stroke
				(width 0.1)
				(type default)
			)
			(layer "F.Fab")
		)
		(fp_line
			(start 0.67945 -0.3048)
			(end 0.67945 0.3048)
			(stroke
				(width 0.1)
				(type default)
			)
			(layer "F.Fab")
		)
		(fp_line
			(start 0.12065 -0.2794)
			(end 0.12065 -0.3048)
			(stroke
				(width 0.1)
				(type default)
			)
			(layer "F.Fab")
		)
		(fp_line
			(start 0.12065 -0.3048)
			(end 0.67945 -0.3048)
			(stroke
				(width 0.1)
				(type default)
			)
			(layer "F.Fab")
		)
		(fp_line
			(start 0.120396 0.3048)
			(end 0.120396 0.2794)
			(stroke
				(width 0.1)
				(type default)
			)
			(layer "F.Fab")
		)
		(fp_line
			(start 0.120396 0.2794)
			(end -0.12065 0.2794)
			(stroke
				(width 0.1)
				(type default)
			)
			(layer "F.Fab")
		)
		(fp_line
			(start -0.12065 0.3048)
			(end -0.67945 0.3048)
			(stroke
				(width 0.1)
				(type default)
			)
			(layer "F.Fab")
		)
		(fp_line
			(start -0.12065 0.2794)
			(end -0.12065 0.3048)
			(stroke
				(width 0.1)
				(type default)
			)
			(layer "F.Fab")
		)
		(fp_line
			(start -0.12065 -0.2794)
			(end 0.12065 -0.2794)
			(stroke
				(width 0.1)
				(type default)
			)
			(layer "F.Fab")
		)
		(fp_line
			(start -0.12065 -0.305054)
			(end -0.12065 -0.2794)
			(stroke
				(width 0.1)
				(type default)
			)
			(layer "F.Fab")
		)
		(fp_line
			(start -0.67945 0.3048)
			(end -0.67945 -0.305054)
			(stroke
				(width 0.1)
				(type default)
			)
			(layer "F.Fab")
		)
		(fp_line
			(start -0.67945 -0.305054)
			(end -0.12065 -0.305054)
			(stroke
				(width 0.1)
				(type default)
			)
			(layer "F.Fab")
		)
		(pad "1" smd circle
			(at -0.40005 0 180)
			(size 0 0)
			(layers "F.Cu" "F.Mask" "F.Paste")
			(net "P12V_NIC6_R")
		)
		(pad "2" smd circle
			(at 0.40005 0 180)
			(size 0 0)
			(layers "F.Cu" "F.Mask" "F.Paste")
			(net "GND")
		)
	)
)
